(kicad_pcb
	(version 20260206)
	(generator "pcbnew")
	(generator_version "10.0")
	(general
		(thickness 1.6)
		(legacy_teardrops no)
	)
	(paper "A4")
	(title_block
		(title "04192023_DAF0TMB3IC0_F0TG_MB_C_brd_V02_OCP.brd")
		(comment 1 "Grand Teton / footprint 827 of 8354 (U6017), pads 337-354 of 354")
	)
	(layers
		(0 "F.Cu" signal "TOP")
		(4 "In1.Cu" signal "GND")
		(6 "In2.Cu" signal "IN1")
		(8 "In3.Cu" signal "GND1")
		(10 "In4.Cu" signal "IN2")
		(12 "In5.Cu" signal "GND2")
		(14 "In6.Cu" signal "IN3")
		(16 "In7.Cu" signal "GND3")
		(18 "In8.Cu" signal "VCC")
		(20 "In9.Cu" signal "VCC1")
		(22 "In10.Cu" signal "GND4")
		(24 "In11.Cu" signal "IN4")
		(26 "In12.Cu" signal "GND5")
		(28 "In13.Cu" signal "IN5")
		(30 "In14.Cu" signal "GND6")
		(32 "In15.Cu" signal "IN6")
		(34 "In16.Cu" signal "GND7")
		(2 "B.Cu" signal "BOTTOM")
		(9 "F.Adhes" user "F.Adhesive")
		(11 "B.Adhes" user "B.Adhesive")
		(13 "F.Paste" user "Package Geometry/Pastemask Top")
		(15 "B.Paste" user "Package Geometry/Pastemask Bottom")
		(5 "F.SilkS" user "Ref Des/Silkscreen Top")
		(7 "B.SilkS" user "Ref Des/Silkscreen Bottom")
		(1 "F.Mask" user "Board Geometry/Soldermask Top")
		(3 "B.Mask" user "Board Geometry/Soldermask Bottom")
		(17 "Dwgs.User" user "User.Drawings")
		(19 "Cmts.User" user "User.Comments")
		(21 "Eco1.User" user "User.Eco1")
		(23 "Eco2.User" user "User.Eco2")
		(25 "Edge.Cuts" user "Board Geometry/Outline")
		(27 "Margin" user)
		(31 "F.CrtYd" user "Package Geometry/Place Bound Top")
		(29 "B.CrtYd" user "Package Geometry/Place Bound Bottom")
		(35 "F.Fab" user "Ref Des/Assembly Top")
		(33 "B.Fab" user "Ref Des/Assembly Bottom")
	)
	(footprint ""
		(layer "F.Cu")
		(at 123.567952 -387.342634)
		(property "Reference" "U6017"
			(at -6.180074 -7.979664 0)
			(unlocked yes)
			(layer "F.SilkS")
			(effects
				(font
					(size 0.7874 0.5842)
					(thickness 0.1524)
				)
				(justify left)
			)
		)
		(property "Value" ""
			(at 0 0 0)
			(layer "F.Fab")
			(effects
				(font
					(size 1.27 1.27)
				)
			)
		)
		(duplicate_pad_numbers_are_jumpers no)
		(pad "P10" smd circle
			(at 8.802624 -1.431798)
			(size 0.381 0.381)
			(layers "F.Cu" "F.Mask" "F.Paste")
			(net "P5E_CPU1_P3_TX_BUF_DN<15>")
		)
		(pad "P29" smd circle
			(at 8.802624 2.032254)
			(size 0.381 0.381)
			(layers "F.Cu" "F.Mask" "F.Paste")
			(net "P5E_CPU1_P3_RX_DN<15>")
		)
		(pad "R1" smd oval
			(at 8.64997 -3.938524)
			(size 0.254 0.3302)
			(layers "F.Cu" "F.Mask" "F.Paste")
			(net "P5E_CPU1_P3_RX_BUF_DP<15>")
		)
		(pad "R35" smd oval
			(at 8.64997 3.940048)
			(size 0.254 0.3302)
			(layers "F.Cu" "F.Mask" "F.Paste")
			(net "P5E_CPU1_P3_TX_C_DP<15>")
		)
		(pad "T4" smd circle
			(at 8.402574 -2.817368)
			(size 0.381 0.381)
			(layers "F.Cu" "F.Mask" "F.Paste")
			(net "GND")
		)
		(pad "T13" smd circle
			(at 8.402574 -0.79629)
			(size 0.3048 0.3048)
			(layers "F.Cu" "F.Mask" "F.Paste")
			(net "GND")
		)
		(pad "T17" smd circle
			(at 8.402574 -0.296164)
			(size 0.3048 0.3048)
			(layers "F.Cu" "F.Mask" "F.Paste")
			(net "P0V9_CPU1_RT3_2A")
		)
		(pad "T20" smd circle
			(at 8.402574 0.203708)
			(size 0.3048 0.3048)
			(layers "F.Cu" "F.Mask" "F.Paste")
			(net "P0V9_CPU1_RT3_2A")
		)
		(pad "T22" smd circle
			(at 8.402574 0.703834)
			(size 0.3048 0.3048)
			(layers "F.Cu" "F.Mask" "F.Paste")
			(net "GND")
		)
		(pad "T32" smd circle
			(at 8.402574 2.724912)
			(size 0.381 0.381)
			(layers "F.Cu" "F.Mask" "F.Paste")
			(net "GND")
		)
		(pad "U2" smd circle
			(at 8.349996 -3.41884)
			(size 0.3048 0.3048)
			(layers "F.Cu" "F.Mask" "F.Paste")
			(net "GND")
		)
		(pad "U34" smd circle
			(at 8.349996 3.420364)
			(size 0.3048 0.3048)
			(layers "F.Cu" "F.Mask" "F.Paste")
			(net "GND")
		)
		(pad "V1" smd oval
			(at 8.050022 -3.938524)
			(size 0.254 0.3302)
			(layers "F.Cu" "F.Mask" "F.Paste")
			(net "GND")
		)
		(pad "V35" smd oval
			(at 8.050022 3.940048)
			(size 0.254 0.3302)
			(layers "F.Cu" "F.Mask" "F.Paste")
			(net "GND")
		)
		(pad "W7" smd circle
			(at 8.002524 -2.12471)
			(size 0.381 0.381)
			(layers "F.Cu" "F.Mask" "F.Paste")
			(net "P5E_CPU1_P3_TX_BUF_DP<14>")
		)
		(pad "W26" smd circle
			(at 8.002524 1.339342)
			(size 0.381 0.381)
			(layers "F.Cu" "F.Mask" "F.Paste")
			(net "P5E_CPU1_P3_RX_DP<14>")
		)
		(pad "Y2" smd circle
			(at 7.750048 -3.41884)
			(size 0.3048 0.3048)
			(layers "F.Cu" "F.Mask" "F.Paste")
			(net "P5E_CPU1_P3_RX_BUF_DN<14>")
		)
		(pad "Y34" smd circle
			(at 7.750048 3.420364)
			(size 0.3048 0.3048)
			(layers "F.Cu" "F.Mask" "F.Paste")
			(net "P5E_CPU1_P3_TX_C_DP<14>")
		)
	)
)
